(kicad_pcb
	(version 20260206)
	(generator "pcbnew")
	(generator_version "10.0")
	(general
		(thickness 1.6)
		(legacy_teardrops no)
	)
	(paper "A4")
	(title_block
		(title "04192023_DAF0TMB3IC0_F0TG_MB_C_brd_V02_OCP.brd")
		(comment 1 "Grand Teton / footprints 6312-6317 of 8354")
	)
	(layers
		(0 "F.Cu" signal "TOP")
		(4 "In1.Cu" signal "GND")
		(6 "In2.Cu" signal "IN1")
		(8 "In3.Cu" signal "GND1")
		(10 "In4.Cu" signal "IN2")
		(12 "In5.Cu" signal "GND2")
		(14 "In6.Cu" signal "IN3")
		(16 "In7.Cu" signal "GND3")
		(18 "In8.Cu" signal "VCC")
		(20 "In9.Cu" signal "VCC1")
		(22 "In10.Cu" signal "GND4")
		(24 "In11.Cu" signal "IN4")
		(26 "In12.Cu" signal "GND5")
		(28 "In13.Cu" signal "IN5")
		(30 "In14.Cu" signal "GND6")
		(32 "In15.Cu" signal "IN6")
		(34 "In16.Cu" signal "GND7")
		(2 "B.Cu" signal "BOTTOM")
		(9 "F.Adhes" user "F.Adhesive")
		(11 "B.Adhes" user "B.Adhesive")
		(13 "F.Paste" user "Package Geometry/Pastemask Top")
		(15 "B.Paste" user "Package Geometry/Pastemask Bottom")
		(5 "F.SilkS" user "Ref Des/Silkscreen Top")
		(7 "B.SilkS" user "Ref Des/Silkscreen Bottom")
		(1 "F.Mask" user "Board Geometry/Soldermask Top")
		(3 "B.Mask" user "Board Geometry/Soldermask Bottom")
		(17 "Dwgs.User" user "User.Drawings")
		(19 "Cmts.User" user "User.Comments")
		(21 "Eco1.User" user "User.Eco1")
		(23 "Eco2.User" user "User.Eco2")
		(25 "Edge.Cuts" user "Board Geometry/Outline")
		(27 "Margin" user)
		(31 "F.CrtYd" user "Package Geometry/Place Bound Top")
		(29 "B.CrtYd" user "Package Geometry/Place Bound Bottom")
		(35 "F.Fab" user "Ref Des/Assembly Top")
		(33 "B.Fab" user "Ref Des/Assembly Bottom")
	)
	(footprint ""
		(layer "B.Cu")
		(at 22.479 -361.061 180)
		(property "Reference" "R8222"
			(at 0 0 0)
			(layer "B.SilkS")
			(hide yes)
			(effects
				(font
					(size 1.27 1.27)
				)
				(justify mirror)
			)
		)
		(property "Value" ""
			(at 0 0 0)
			(layer "B.Fab")
			(effects
				(font
					(size 1.27 1.27)
				)
				(justify mirror)
			)
		)
		(duplicate_pad_numbers_are_jumpers no)
		(fp_line
			(start 0.7874 0.4064)
			(end 0.7874 -0.4064)
			(stroke
				(width 0.1524)
				(type default)
			)
			(layer "B.SilkS")
		)
		(fp_line
			(start 0.7874 -0.4064)
			(end -0.7874 -0.4064)
			(stroke
				(width 0.1524)
				(type default)
			)
			(layer "B.SilkS")
		)
		(fp_line
			(start -0.7874 0.4064)
			(end 0.7874 0.4064)
			(stroke
				(width 0.1524)
				(type default)
			)
			(layer "B.SilkS")
		)
		(fp_line
			(start -0.7874 -0.4064)
			(end -0.7874 0.4064)
			(stroke
				(width 0.1524)
				(type default)
			)
			(layer "B.SilkS")
		)
		(fp_line
			(start 0.67945 0.3048)
			(end 0.67945 -0.305054)
			(stroke
				(width 0.1)
				(type default)
			)
			(layer "B.Fab")
		)
		(fp_line
			(start 0.67945 -0.305054)
			(end 0.12065 -0.305054)
			(stroke
				(width 0.1)
				(type default)
			)
			(layer "B.Fab")
		)
		(fp_line
			(start 0.12065 0.3048)
			(end 0.67945 0.3048)
			(stroke
				(width 0.1)
				(type default)
			)
			(layer "B.Fab")
		)
		(fp_line
			(start 0.12065 0.2794)
			(end 0.12065 0.3048)
			(stroke
				(width 0.1)
				(type default)
			)
			(layer "B.Fab")
		)
		(fp_line
			(start 0.12065 -0.2794)
			(end -0.12065 -0.2794)
			(stroke
				(width 0.1)
				(type default)
			)
			(layer "B.Fab")
		)
		(fp_line
			(start 0.12065 -0.305054)
			(end 0.12065 -0.2794)
			(stroke
				(width 0.1)
				(type default)
			)
			(layer "B.Fab")
		)
		(fp_line
			(start -0.120396 0.3048)
			(end -0.120396 0.2794)
			(stroke
				(width 0.1)
				(type default)
			)
			(layer "B.Fab")
		)
		(fp_line
			(start -0.120396 0.2794)
			(end 0.12065 0.2794)
			(stroke
				(width 0.1)
				(type default)
			)
			(layer "B.Fab")
		)
		(fp_line
			(start -0.12065 -0.2794)
			(end -0.12065 -0.3048)
			(stroke
				(width 0.1)
				(type default)
			)
			(layer "B.Fab")
		)
		(fp_line
			(start -0.12065 -0.3048)
			(end -0.67945 -0.3048)
			(stroke
				(width 0.1)
				(type default)
			)
			(layer "B.Fab")
		)
		(fp_line
			(start -0.67945 0.3048)
			(end -0.120396 0.3048)
			(stroke
				(width 0.1)
				(type default)
			)
			(layer "B.Fab")
		)
		(fp_line
			(start -0.67945 -0.3048)
			(end -0.67945 0.3048)
			(stroke
				(width 0.1)
				(type default)
			)
			(layer "B.Fab")
		)
		(pad "1" smd circle
			(at 0.40005 0)
			(size 0 0)
			(layers "B.Cu" "B.Mask" "B.Paste")
			(net "PVDD18_S5_P1")
		)
		(pad "2" smd circle
			(at -0.40005 0)
			(size 0 0)
			(layers "B.Cu" "B.Mask" "B.Paste")
			(net "SVID_PVDDCR_CPU1_P1_SVD_R")
		)
	)
	(footprint ""
		(layer "B.Cu")
		(at 345.510612 -169.787062 90)
		(property "Reference" "PC166_6"
			(at 0 0 90)
			(layer "B.SilkS")
			(hide yes)
			(effects
				(font
					(size 1.27 1.27)
				)
				(justify mirror)
			)
		)
		(property "Value" ""
			(at 0 0 90)
			(layer "B.Fab")
			(effects
				(font
					(size 1.27 1.27)
				)
				(justify mirror)
			)
		)
		(duplicate_pad_numbers_are_jumpers no)
		(fp_line
			(start 1.524 -0.762)
			(end -1.524 -0.762)
			(stroke
				(width 0.1524)
				(type default)
			)
			(layer "B.SilkS")
		)
		(fp_line
			(start -1.524 -0.762)
			(end -1.524 0.762)
			(stroke
				(width 0.1524)
				(type default)
			)
			(layer "B.SilkS")
		)
		(fp_line
			(start 1.524 0.762)
			(end 1.524 -0.762)
			(stroke
				(width 0.1524)
				(type default)
			)
			(layer "B.SilkS")
		)
		(fp_line
			(start -1.524 0.762)
			(end 1.524 0.762)
			(stroke
				(width 0.1524)
				(type default)
			)
			(layer "B.SilkS")
		)
		(fp_line
			(start 1.1049 -0.724916)
			(end 1.1049 0.724916)
			(stroke
				(width 0.1)
				(type default)
			)
			(layer "B.Fab")
		)
		(fp_line
			(start -1.1049 -0.724916)
			(end 1.1049 -0.724916)
			(stroke
				(width 0.1)
				(type default)
			)
			(layer "B.Fab")
		)
		(fp_line
			(start 1.1049 0.724916)
			(end -1.1049 0.724916)
			(stroke
				(width 0.1)
				(type default)
			)
			(layer "B.Fab")
		)
		(fp_line
			(start -1.1049 0.724916)
			(end -1.1049 -0.724916)
			(stroke
				(width 0.1)
				(type default)
			)
			(layer "B.Fab")
		)
		(pad "1" smd rect
			(at 0.889 0 90)
			(size 1.016 1.27)
			(layers "B.Cu" "B.Mask" "B.Paste")
			(net "PVDDCR_CPU0_P0")
		)
		(pad "2" smd rect
			(at -0.889 0 90)
			(size 1.016 1.27)
			(layers "B.Cu" "B.Mask" "B.Paste")
			(net "GND")
		)
	)
	(footprint ""
		(layer "B.Cu")
		(at 25.146 -367.157 90)
		(property "Reference" "R8233"
			(at 0 0 90)
			(layer "B.SilkS")
			(hide yes)
			(effects
				(font
					(size 1.27 1.27)
				)
				(justify mirror)
			)
		)
		(property "Value" ""
			(at 0 0 90)
			(layer "B.Fab")
			(effects
				(font
					(size 1.27 1.27)
				)
				(justify mirror)
			)
		)
		(duplicate_pad_numbers_are_jumpers no)
		(fp_line
			(start 0.7874 -0.4064)
			(end -0.7874 -0.4064)
			(stroke
				(width 0.1524)
				(type default)
			)
			(layer "B.SilkS")
		)
		(fp_line
			(start -0.7874 -0.4064)
			(end -0.7874 0.4064)
			(stroke
				(width 0.1524)
				(type default)
			)
			(layer "B.SilkS")
		)
		(fp_line
			(start 0.7874 0.4064)
			(end 0.7874 -0.4064)
			(stroke
				(width 0.1524)
				(type default)
			)
			(layer "B.SilkS")
		)
		(fp_line
			(start -0.7874 0.4064)
			(end 0.7874 0.4064)
			(stroke
				(width 0.1524)
				(type default)
			)
			(layer "B.SilkS")
		)
		(fp_line
			(start 0.67945 -0.305054)
			(end 0.12065 -0.305054)
			(stroke
				(width 0.1)
				(type default)
			)
			(layer "B.Fab")
		)
		(fp_line
			(start 0.12065 -0.305054)
			(end 0.12065 -0.2794)
			(stroke
				(width 0.1)
				(type default)
			)
			(layer "B.Fab")
		)
		(fp_line
			(start -0.12065 -0.3048)
			(end -0.67945 -0.3048)
			(stroke
				(width 0.1)
				(type default)
			)
			(layer "B.Fab")
		)
		(fp_line
			(start -0.67945 -0.3048)
			(end -0.67945 0.3048)
			(stroke
				(width 0.1)
				(type default)
			)
			(layer "B.Fab")
		)
		(fp_line
			(start 0.12065 -0.2794)
			(end -0.12065 -0.2794)
			(stroke
				(width 0.1)
				(type default)
			)
			(layer "B.Fab")
		)
		(fp_line
			(start -0.12065 -0.2794)
			(end -0.12065 -0.3048)
			(stroke
				(width 0.1)
				(type default)
			)
			(layer "B.Fab")
		)
		(fp_line
			(start 0.12065 0.2794)
			(end 0.12065 0.3048)
			(stroke
				(width 0.1)
				(type default)
			)
			(layer "B.Fab")
		)
		(fp_line
			(start -0.120396 0.2794)
			(end 0.12065 0.2794)
			(stroke
				(width 0.1)
				(type default)
			)
			(layer "B.Fab")
		)
		(fp_line
			(start 0.67945 0.3048)
			(end 0.67945 -0.305054)
			(stroke
				(width 0.1)
				(type default)
			)
			(layer "B.Fab")
		)
		(fp_line
			(start 0.12065 0.3048)
			(end 0.67945 0.3048)
			(stroke
				(width 0.1)
				(type default)
			)
			(layer "B.Fab")
		)
		(fp_line
			(start -0.120396 0.3048)
			(end -0.120396 0.2794)
			(stroke
				(width 0.1)
				(type default)
			)
			(layer "B.Fab")
		)
		(fp_line
			(start -0.67945 0.3048)
			(end -0.120396 0.3048)
			(stroke
				(width 0.1)
				(type default)
			)
			(layer "B.Fab")
		)
		(pad "1" smd circle
			(at 0.40005 0 270)
			(size 0 0)
			(layers "B.Cu" "B.Mask" "B.Paste")
			(net "P3V3_AUX")
		)
		(pad "2" smd circle
			(at -0.40005 0 270)
			(size 0 0)
			(layers "B.Cu" "B.Mask" "B.Paste")
			(net "PWRGD_PVDDCR_CPU1_P1_R")
		)
	)
	(footprint ""
		(layer "B.Cu")
		(at 174.64024 -100.294948 -90)
		(property "Reference" "R244"
			(at 0 0 90)
			(layer "B.SilkS")
			(hide yes)
			(effects
				(font
					(size 1.27 1.27)
				)
				(justify mirror)
			)
		)
		(property "Value" ""
			(at 0 0 90)
			(layer "B.Fab")
			(effects
				(font
					(size 1.27 1.27)
				)
				(justify mirror)
			)
		)
		(duplicate_pad_numbers_are_jumpers no)
		(fp_line
			(start -0.7874 0.4064)
			(end 0.7874 0.4064)
			(stroke
				(width 0.1524)
				(type default)
			)
			(layer "B.SilkS")
		)
		(fp_line
			(start 0.7874 0.4064)
			(end 0.7874 -0.4064)
			(stroke
				(width 0.1524)
				(type default)
			)
			(layer "B.SilkS")
		)
		(fp_line
			(start -0.7874 -0.4064)
			(end -0.7874 0.4064)
			(stroke
				(width 0.1524)
				(type default)
			)
			(layer "B.SilkS")
		)
		(fp_line
			(start 0.7874 -0.4064)
			(end -0.7874 -0.4064)
			(stroke
				(width 0.1524)
				(type default)
			)
			(layer "B.SilkS")
		)
		(fp_line
			(start -0.67945 0.3048)
			(end -0.120396 0.3048)
			(stroke
				(width 0.1)
				(type default)
			)
			(layer "B.Fab")
		)
		(fp_line
			(start -0.120396 0.3048)
			(end -0.120396 0.2794)
			(stroke
				(width 0.1)
				(type default)
			)
			(layer "B.Fab")
		)
		(fp_line
			(start 0.12065 0.3048)
			(end 0.67945 0.3048)
			(stroke
				(width 0.1)
				(type default)
			)
			(layer "B.Fab")
		)
		(fp_line
			(start 0.67945 0.3048)
			(end 0.67945 -0.305054)
			(stroke
				(width 0.1)
				(type default)
			)
			(layer "B.Fab")
		)
		(fp_line
			(start -0.120396 0.2794)
			(end 0.12065 0.2794)
			(stroke
				(width 0.1)
				(type default)
			)
			(layer "B.Fab")
		)
		(fp_line
			(start 0.12065 0.2794)
			(end 0.12065 0.3048)
			(stroke
				(width 0.1)
				(type default)
			)
			(layer "B.Fab")
		)
		(fp_line
			(start -0.12065 -0.2794)
			(end -0.12065 -0.3048)
			(stroke
				(width 0.1)
				(type default)
			)
			(layer "B.Fab")
		)
		(fp_line
			(start 0.12065 -0.2794)
			(end -0.12065 -0.2794)
			(stroke
				(width 0.1)
				(type default)
			)
			(layer "B.Fab")
		)
		(fp_line
			(start -0.67945 -0.3048)
			(end -0.67945 0.3048)
			(stroke
				(width 0.1)
				(type default)
			)
			(layer "B.Fab")
		)
		(fp_line
			(start -0.12065 -0.3048)
			(end -0.67945 -0.3048)
			(stroke
				(width 0.1)
				(type default)
			)
			(layer "B.Fab")
		)
		(fp_line
			(start 0.12065 -0.305054)
			(end 0.12065 -0.2794)
			(stroke
				(width 0.1)
				(type default)
			)
			(layer "B.Fab")
		)
		(fp_line
			(start 0.67945 -0.305054)
			(end 0.12065 -0.305054)
			(stroke
				(width 0.1)
				(type default)
			)
			(layer "B.Fab")
		)
		(pad "1" smd circle
			(at 0.40005 0 90)
			(size 0 0)
			(layers "B.Cu" "B.Mask" "B.Paste")
			(net "IRQ_BMC_SMI_N")
		)
		(pad "2" smd circle
			(at -0.40005 0 90)
			(size 0 0)
			(layers "B.Cu" "B.Mask" "B.Paste")
			(net "IRQ_BMC_SMI_R_N")
		)
	)
	(footprint ""
		(layer "B.Cu")
		(at 105.537 -421.005 180)
		(property "Reference" "R3514"
			(at 0 0 0)
			(layer "B.SilkS")
			(hide yes)
			(effects
				(font
					(size 1.27 1.27)
				)
				(justify mirror)
			)
		)
		(property "Value" ""
			(at 0 0 0)
			(layer "B.Fab")
			(effects
				(font
					(size 1.27 1.27)
				)
				(justify mirror)
			)
		)
		(duplicate_pad_numbers_are_jumpers no)
		(fp_line
			(start 0.7874 0.4064)
			(end 0.7874 -0.4064)
			(stroke
				(width 0.1524)
				(type default)
			)
			(layer "B.SilkS")
		)
		(fp_line
			(start 0.7874 -0.4064)
			(end -0.7874 -0.4064)
			(stroke
				(width 0.1524)
				(type default)
			)
			(layer "B.SilkS")
		)
		(fp_line
			(start -0.7874 0.4064)
			(end 0.7874 0.4064)
			(stroke
				(width 0.1524)
				(type default)
			)
			(layer "B.SilkS")
		)
		(fp_line
			(start -0.7874 -0.4064)
			(end -0.7874 0.4064)
			(stroke
				(width 0.1524)
				(type default)
			)
			(layer "B.SilkS")
		)
		(fp_line
			(start 0.67945 0.3048)
			(end 0.67945 -0.305054)
			(stroke
				(width 0.1)
				(type default)
			)
			(layer "B.Fab")
		)
		(fp_line
			(start 0.67945 -0.305054)
			(end 0.12065 -0.305054)
			(stroke
				(width 0.1)
				(type default)
			)
			(layer "B.Fab")
		)
		(fp_line
			(start 0.12065 0.3048)
			(end 0.67945 0.3048)
			(stroke
				(width 0.1)
				(type default)
			)
			(layer "B.Fab")
		)
		(fp_line
			(start 0.12065 0.2794)
			(end 0.12065 0.3048)
			(stroke
				(width 0.1)
				(type default)
			)
			(layer "B.Fab")
		)
		(fp_line
			(start 0.12065 -0.2794)
			(end -0.12065 -0.2794)
			(stroke
				(width 0.1)
				(type default)
			)
			(layer "B.Fab")
		)
		(fp_line
			(start 0.12065 -0.305054)
			(end 0.12065 -0.2794)
			(stroke
				(width 0.1)
				(type default)
			)
			(layer "B.Fab")
		)
		(fp_line
			(start -0.120396 0.3048)
			(end -0.120396 0.2794)
			(stroke
				(width 0.1)
				(type default)
			)
			(layer "B.Fab")
		)
		(fp_line
			(start -0.120396 0.2794)
			(end 0.12065 0.2794)
			(stroke
				(width 0.1)
				(type default)
			)
			(layer "B.Fab")
		)
		(fp_line
			(start -0.12065 -0.2794)
			(end -0.12065 -0.3048)
			(stroke
				(width 0.1)
				(type default)
			)
			(layer "B.Fab")
		)
		(fp_line
			(start -0.12065 -0.3048)
			(end -0.67945 -0.3048)
			(stroke
				(width 0.1)
				(type default)
			)
			(layer "B.Fab")
		)
		(fp_line
			(start -0.67945 0.3048)
			(end -0.120396 0.3048)
			(stroke
				(width 0.1)
				(type default)
			)
			(layer "B.Fab")
		)
		(fp_line
			(start -0.67945 -0.3048)
			(end -0.67945 0.3048)
			(stroke
				(width 0.1)
				(type default)
			)
			(layer "B.Fab")
		)
		(pad "1" smd circle
			(at 0.40005 0)
			(size 0 0)
			(layers "B.Cu" "B.Mask" "B.Paste")
			(net "P3V3_AUX")
		)
		(pad "2" smd circle
			(at -0.40005 0)
			(size 0 0)
			(layers "B.Cu" "B.Mask" "B.Paste")
			(net "FM_SMB_2_ALERT_GPU_N")
		)
	)
	(footprint ""
		(layer "B.Cu")
		(at 97.591118 -424.191684)
		(property "Reference" "R8001"
			(at 0 0 0)
			(layer "B.SilkS")
			(hide yes)
			(effects
				(font
					(size 1.27 1.27)
				)
				(justify mirror)
			)
		)
		(property "Value" ""
			(at 0 0 0)
			(layer "B.Fab")
			(effects
				(font
					(size 1.27 1.27)
				)
				(justify mirror)
			)
		)
		(duplicate_pad_numbers_are_jumpers no)
		(fp_line
			(start -0.7874 -0.4064)
			(end -0.7874 0.4064)
			(stroke
				(width 0.1524)
				(type default)
			)
			(layer "B.SilkS")
		)
		(fp_line
			(start -0.7874 0.4064)
			(end 0.7874 0.4064)
			(stroke
				(width 0.1524)
				(type default)
			)
			(layer "B.SilkS")
		)
		(fp_line
			(start 0.7874 -0.4064)
			(end -0.7874 -0.4064)
			(stroke
				(width 0.1524)
				(type default)
			)
			(layer "B.SilkS")
		)
		(fp_line
			(start 0.7874 0.4064)
			(end 0.7874 -0.4064)
			(stroke
				(width 0.1524)
				(type default)
			)
			(layer "B.SilkS")
		)
		(fp_line
			(start -0.67945 -0.3048)
			(end -0.67945 0.3048)
			(stroke
				(width 0.1)
				(type default)
			)
			(layer "B.Fab")
		)
		(fp_line
			(start -0.67945 0.3048)
			(end -0.120396 0.3048)
			(stroke
				(width 0.1)
				(type default)
			)
			(layer "B.Fab")
		)
		(fp_line
			(start -0.12065 -0.3048)
			(end -0.67945 -0.3048)
			(stroke
				(width 0.1)
				(type default)
			)
			(layer "B.Fab")
		)
		(fp_line
			(start -0.12065 -0.2794)
			(end -0.12065 -0.3048)
			(stroke
				(width 0.1)
				(type default)
			)
			(layer "B.Fab")
		)
		(fp_line
			(start -0.120396 0.2794)
			(end 0.12065 0.2794)
			(stroke
				(width 0.1)
				(type default)
			)
			(layer "B.Fab")
		)
		(fp_line
			(start -0.120396 0.3048)
			(end -0.120396 0.2794)
			(stroke
				(width 0.1)
				(type default)
			)
			(layer "B.Fab")
		)
		(fp_line
			(start 0.12065 -0.305054)
			(end 0.12065 -0.2794)
			(stroke
				(width 0.1)
				(type default)
			)
			(layer "B.Fab")
		)
		(fp_line
			(start 0.12065 -0.2794)
			(end -0.12065 -0.2794)
			(stroke
				(width 0.1)
				(type default)
			)
			(layer "B.Fab")
		)
		(fp_line
			(start 0.12065 0.2794)
			(end 0.12065 0.3048)
			(stroke
				(width 0.1)
				(type default)
			)
			(layer "B.Fab")
		)
		(fp_line
			(start 0.12065 0.3048)
			(end 0.67945 0.3048)
			(stroke
				(width 0.1)
				(type default)
			)
			(layer "B.Fab")
		)
		(fp_line
			(start 0.67945 -0.305054)
			(end 0.12065 -0.305054)
			(stroke
				(width 0.1)
				(type default)
			)
			(layer "B.Fab")
		)
		(fp_line
			(start 0.67945 0.3048)
			(end 0.67945 -0.305054)
			(stroke
				(width 0.1)
				(type default)
			)
			(layer "B.Fab")
		)
		(pad "1" smd circle
			(at 0.40005 0 180)
			(size 0 0)
			(layers "B.Cu" "B.Mask" "B.Paste")
			(net "PRSNT_SWB_N")
		)
		(pad "2" smd circle
			(at -0.40005 0 180)
			(size 0 0)
			(layers "B.Cu" "B.Mask" "B.Paste")
			(net "GND")
		)
	)
)
